# S9S_MB_2U (Grand Teton) — schematic netlist excerpt (pin names and nets, part order shuffled) for the footprints in the layout excerpt that follows; sources: Cadence DE-HDL packaged netlist, KiCad conversion of 03242023_DA0F0TMBIJ0_F0T_Motherboard_J_brd_V01_OCP.brd

R4481  Q_RES  33.2 1% CHIP  pkg 0402LF  page 237 : A = SMB_HOST_CLK_BUF_ISO_3V3AUX_SDA ; B = SMB_HOST_9ZXL045_3V3AUX_SDA

Q35  MOSFET_NCH_GDS_ESD_PROTECTED  2N7002K IC  pkg SOT23_GDSXC  page 185
  D  = RST_SRTCRST_N
  G  = RST_PFR_OVR_SRTC
  S  = GND

(kicad_pcb
	(version 20260206)
	(generator "pcbnew")
	(generator_version "10.0")
	(general
		(thickness 1.6)
		(legacy_teardrops no)
	)
	(paper "A4")
	(title_block
		(title "03242023_DA0F0TMBIJ0_F0T_Motherboard_J_brd_V01_OCP.brd")
		(comment 1 "Grand Teton / footprints 1119-1120 of 6105")
	)
	(layers
		(0 "F.Cu" signal "TOP")
		(4 "In1.Cu" signal "GND")
		(6 "In2.Cu" signal "IN1")
		(8 "In3.Cu" signal "GND1")
		(10 "In4.Cu" signal "IN2")
		(12 "In5.Cu" signal "GND2")
		(14 "In6.Cu" signal "IN3")
		(16 "In7.Cu" signal "GND3")
		(18 "In8.Cu" signal "VCC")
		(20 "In9.Cu" signal "VCC1")
		(22 "In10.Cu" signal "GND4")
		(24 "In11.Cu" signal "IN4")
		(26 "In12.Cu" signal "GND5")
		(28 "In13.Cu" signal "IN5")
		(30 "In14.Cu" signal "GND6")
		(32 "In15.Cu" signal "IN6")
		(34 "In16.Cu" signal "GND7")
		(2 "B.Cu" signal "BOTTOM")
		(9 "F.Adhes" user "F.Adhesive")
		(11 "B.Adhes" user "B.Adhesive")
		(13 "F.Paste" user "Package Geometry/Pastemask Top")
		(15 "B.Paste" user "Package Geometry/Pastemask Bottom")
		(5 "F.SilkS" user "Ref Des/Silkscreen Top")
		(7 "B.SilkS" user "Ref Des/Silkscreen Bottom")
		(1 "F.Mask" user "Board Geometry/Soldermask Top")
		(3 "B.Mask" user "Board Geometry/Soldermask Bottom")
		(17 "Dwgs.User" user "User.Drawings")
		(19 "Cmts.User" user "User.Comments")
		(21 "Eco1.User" user "User.Eco1")
		(23 "Eco2.User" user "User.Eco2")
		(25 "Edge.Cuts" user "Board Geometry/Outline")
		(27 "Margin" user)
		(31 "F.CrtYd" user "Package Geometry/Place Bound Top")
		(29 "B.CrtYd" user "Package Geometry/Place Bound Bottom")
		(35 "F.Fab" user "Ref Des/Assembly Top")
		(33 "B.Fab" user "Ref Des/Assembly Bottom")
	)
	(footprint ""
		(layer "F.Cu")
		(at 205.968092 -104.715056)
		(property "Reference" "Q35"
			(at -1.651 -2.25933 0)
			(unlocked yes)
			(layer "F.SilkS")
			(effects
				(font
					(size 0.7874 0.5842)
					(thickness 0.1524)
				)
				(justify left)
			)
		)
		(property "Value" ""
			(at 0 0 0)
			(layer "F.Fab")
			(effects
				(font
					(size 1.27 1.27)
				)
			)
		)
		(duplicate_pad_numbers_are_jumpers no)
		(fp_line
			(start -1.603248 -1.500124)
			(end 1.603248 -1.500124)
			(stroke
				(width 0.1524)
				(type default)
			)
			(layer "F.SilkS")
		)
		(fp_line
			(start -1.603248 1.500124)
			(end -1.603248 -1.500124)
			(stroke
				(width 0.1524)
				(type default)
			)
			(layer "F.SilkS")
		)
		(fp_line
			(start 1.603248 -1.500124)
			(end 1.603248 1.500124)
			(stroke
				(width 0.1524)
				(type default)
			)
			(layer "F.SilkS")
		)
		(fp_line
			(start 1.603248 1.500124)
			(end -1.603248 1.500124)
			(stroke
				(width 0.1524)
				(type default)
			)
			(layer "F.SilkS")
		)
		(fp_line
			(start -1.249934 -1.169924)
			(end -1.249934 -0.729996)
			(stroke
				(width 0.1)
				(type default)
			)
			(layer "F.Fab")
		)
		(fp_line
			(start -1.249934 -0.729996)
			(end -0.6985 -0.729996)
			(stroke
				(width 0.1)
				(type default)
			)
			(layer "F.Fab")
		)
		(fp_line
			(start -1.249934 0.729996)
			(end -1.249934 1.169924)
			(stroke
				(width 0.1)
				(type default)
			)
			(layer "F.Fab")
		)
		(fp_line
			(start -1.249934 1.169924)
			(end -0.700024 1.169924)
			(stroke
				(width 0.1)
				(type default)
			)
			(layer "F.Fab")
		)
		(fp_line
			(start -0.700024 -1.500124)
			(end -0.700024 -1.169924)
			(stroke
				(width 0.1)
				(type default)
			)
			(layer "F.Fab")
		)
		(fp_line
			(start -0.700024 -1.169924)
			(end -1.249934 -1.169924)
			(stroke
				(width 0.1)
				(type default)
			)
			(layer "F.Fab")
		)
		(fp_line
			(start -0.700024 1.169924)
			(end -0.700024 1.500124)
			(stroke
				(width 0.1)
				(type default)
			)
			(layer "F.Fab")
		)
		(fp_line
			(start -0.700024 1.500124)
			(end 0.700024 1.500124)
			(stroke
				(width 0.1)
				(type default)
			)
			(layer "F.Fab")
		)
		(fp_line
			(start -0.6985 -0.729996)
			(end -0.6985 0.729996)
			(stroke
				(width 0.1)
				(type default)
			)
			(layer "F.Fab")
		)
		(fp_line
			(start -0.6985 0.729996)
			(end -1.249934 0.729996)
			(stroke
				(width 0.1)
				(type default)
			)
			(layer "F.Fab")
		)
		(fp_line
			(start 0.700024 -1.500124)
			(end -0.700024 -1.500124)
			(stroke
				(width 0.1)
				(type default)
			)
			(layer "F.Fab")
		)
		(fp_line
			(start 0.700024 -0.219964)
			(end 0.700024 -1.500124)
			(stroke
				(width 0.1)
				(type default)
			)
			(layer "F.Fab")
		)
		(fp_line
			(start 0.700024 0.219964)
			(end 1.249934 0.219964)
			(stroke
				(width 0.1)
				(type default)
			)
			(layer "F.Fab")
		)
		(fp_line
			(start 0.700024 1.500124)
			(end 0.700024 0.219964)
			(stroke
				(width 0.1)
				(type default)
			)
			(layer "F.Fab")
		)
		(fp_line
			(start 1.249934 -0.219964)
			(end 0.700024 -0.219964)
			(stroke
				(width 0.1)
				(type default)
			)
			(layer "F.Fab")
		)
		(fp_line
			(start 1.249934 0.219964)
			(end 1.249934 -0.219964)
			(stroke
				(width 0.1)
				(type default)
			)
			(layer "F.Fab")
		)
		(fp_rect
			(start -0.700024 1.500124)
			(end 0.700024 -1.500124)
			(stroke
				(width 0)
				(type default)
			)
			(fill no)
			(layer "F.Fab")
		)
		(pad "D" smd rect
			(at 0.999998 0 270)
			(size 0.8128 0.9144)
			(layers "F.Cu" "F.Mask" "F.Paste")
			(net "RST_SRTCRST_N")
		)
		(pad "G" smd rect
			(at -0.999998 -0.94996 270)
			(size 0.8128 0.9144)
			(layers "F.Cu" "F.Mask" "F.Paste")
			(net "RST_PFR_OVR_SRTC")
		)
		(pad "S" smd rect
			(at -0.999998 0.94996 270)
			(size 0.8128 0.9144)
			(layers "F.Cu" "F.Mask" "F.Paste")
			(net "GND")
		)
	)
	(footprint ""
		(layer "F.Cu")
		(at 120.0912 -415.276538 180)
		(property "Reference" "R4481"
			(at 0 0 180)
			(layer "F.SilkS")
			(hide yes)
			(effects
				(font
					(size 1.27 1.27)
				)
			)
		)
		(property "Value" ""
			(at 0 0 180)
			(layer "F.Fab")
			(effects
				(font
					(size 1.27 1.27)
				)
			)
		)
		(duplicate_pad_numbers_are_jumpers no)
		(fp_line
			(start 0.7874 0.4064)
			(end -0.7874 0.4064)
			(stroke
				(width 0.1524)
				(type default)
			)
			(layer "F.SilkS")
		)
		(fp_line
			(start 0.7874 -0.4064)
			(end 0.7874 0.4064)
			(stroke
				(width 0.1524)
				(type default)
			)
			(layer "F.SilkS")
		)
		(fp_line
			(start -0.7874 0.4064)
			(end -0.7874 -0.4064)
			(stroke
				(width 0.1524)
				(type default)
			)
			(layer "F.SilkS")
		)
		(fp_line
			(start -0.7874 -0.4064)
			(end 0.7874 -0.4064)
			(stroke
				(width 0.1524)
				(type default)
			)
			(layer "F.SilkS")
		)
		(fp_line
			(start 0.67945 0.3048)
			(end 0.120396 0.3048)
			(stroke
				(width 0.1)
				(type default)
			)
			(layer "F.Fab")
		)
		(fp_line
			(start 0.67945 -0.3048)
			(end 0.67945 0.3048)
			(stroke
				(width 0.1)
				(type default)
			)
			(layer "F.Fab")
		)
		(fp_line
			(start 0.12065 -0.2794)
			(end 0.12065 -0.3048)
			(stroke
				(width 0.1)
				(type default)
			)
			(layer "F.Fab")
		)
		(fp_line
			(start 0.12065 -0.3048)
			(end 0.67945 -0.3048)
			(stroke
				(width 0.1)
				(type default)
			)
			(layer "F.Fab")
		)
		(fp_line
			(start 0.120396 0.3048)
			(end 0.120396 0.2794)
			(stroke
				(width 0.1)
				(type default)
			)
			(layer "F.Fab")
		)
		(fp_line
			(start 0.120396 0.2794)
			(end -0.12065 0.2794)
			(stroke
				(width 0.1)
				(type default)
			)
			(layer "F.Fab")
		)
		(fp_line
			(start -0.12065 0.3048)
			(end -0.67945 0.3048)
			(stroke
				(width 0.1)
				(type default)
			)
			(layer "F.Fab")
		)
		(fp_line
			(start -0.12065 0.2794)
			(end -0.12065 0.3048)
			(stroke
				(width 0.1)
				(type default)
			)
			(layer "F.Fab")
		)
		(fp_line
			(start -0.12065 -0.2794)
			(end 0.12065 -0.2794)
			(stroke
				(width 0.1)
				(type default)
			)
			(layer "F.Fab")
		)
		(fp_line
			(start -0.12065 -0.305054)
			(end -0.12065 -0.2794)
			(stroke
				(width 0.1)
				(type default)
			)
			(layer "F.Fab")
		)
		(fp_line
			(start -0.67945 0.3048)
			(end -0.67945 -0.305054)
			(stroke
				(width 0.1)
				(type default)
			)
			(layer "F.Fab")
		)
		(fp_line
			(start -0.67945 -0.305054)
			(end -0.12065 -0.305054)
			(stroke
				(width 0.1)
				(type default)
			)
			(layer "F.Fab")
		)
		(pad "1" smd circle
			(at -0.40005 0 180)
			(size 0 0)
			(layers "F.Cu" "F.Mask" "F.Paste")
			(net "SMB_HOST_CLK_BUF_ISO_3V3AUX_SDA")
		)
		(pad "2" smd circle
			(at 0.40005 0 180)
			(size 0 0)
			(layers "F.Cu" "F.Mask" "F.Paste")
			(net "SMB_HOST_9ZXL045_3V3AUX_SDA")
		)
	)
)
